# S9S_MB_2U (Grand Teton) — schematic netlist excerpt (pin names and nets, part order shuffled) for the footprints in the layout excerpt that follows; sources: Cadence DE-HDL packaged netlist, KiCad conversion of 03242023_DA0F0TMBIJ0_F0T_Motherboard_J_brd_V01_OCP.brd

J32  SCONN288_ADR50017P087CC  SCONN288_ADR50017-P087CC IO  pkg DDR288S_1-1VXB  page 113
  VIN_BULK0  = P12V_S3_AUX_CPU1_NVDIMM
  RFU0  = TP_CHH_CPU1_DIMM2_FRU_0
  VIN_MGMT  = P3V3_AUX
  HSCL  = I3C_SPD_DDREFGH_CPU1_LVC1_SCL_7
  HSDA  = I3C_SPD_DDREFGH_CPU1_LVC1_SDA
  VSS0  = GND
  DQ0_A  = M_H_CPU1_SA_DQ<0>
  VSS1  = GND
  DQ1_A  = M_H_CPU1_SA_DQ<1>
  VSS2  = GND
  DQS0_A_T  = M_H_CPU1_SA_DQS_DP<0>
  DQS0_A_C  = M_H_CPU1_SA_DQS_DN<0>
  VSS3  = GND
  DQ4_A  = M_H_CPU1_SA_DQ<4>
  VSS4  = GND
  DQ5_A  = M_H_CPU1_SA_DQ<5>
  VSS5  = GND
  DQ8_A  = M_H_CPU1_SA_DQ<8>
  VSS6  = GND
  DQ9_A  = M_H_CPU1_SA_DQ<9>
  VSS7  = GND
  DQS1_A_T  = M_H_CPU1_SA_DQS_DP<1>
  DQS1_A_C  = M_H_CPU1_SA_DQS_DN<1>
  VSS8  = GND
  DQ12_A  = M_H_CPU1_SA_DQ<12>
  VSS9  = GND
  DQ13_A  = M_H_CPU1_SA_DQ<13>
  VSS10  = GND
  DQ16_A  = M_H_CPU1_SA_DQ<16>
  VSS11  = GND
  DQ17_A  = M_H_CPU1_SA_DQ<17>
  VSS12  = GND
  DQS2_A_T  = M_H_CPU1_SA_DQS_DP<2>
  DQS2_A_C  = M_H_CPU1_SA_DQS_DN<2>
  VSS13  = GND
  DQ20_A  = M_H_CPU1_SA_DQ<20>
  VSS14  = GND
  DQ21_A  = M_H_CPU1_SA_DQ<21>
  VSS15  = GND
  DQ24_A  = M_H_CPU1_SA_DQ<24>
  VSS16  = GND
  DQ25_A  = M_H_CPU1_SA_DQ<25>
  VSS17  = GND
  DQS3_A_T  = M_H_CPU1_SA_DQS_DP<3>
  DQS3_A_C  = M_H_CPU1_SA_DQS_DN<3>
  VSS18  = GND
  DQ28_A  = M_H_CPU1_SA_DQ<28>
  VSS19  = GND
  DQ29_A  = M_H_CPU1_SA_DQ<29>
  VSS20  = GND
  CB0_A  = M_H_CPU1_SA_CB<0>
  VSS21  = GND
  CB1_A  = M_H_CPU1_SA_CB<1>
  VSS22  = GND
  DQS4_A_T  = M_H_CPU1_SA_DQS_DP<4>
  DQS4_A_C  = M_H_CPU1_SA_DQS_DN<4>
  VSS23  = GND
  CB4_A  = M_H_CPU1_SA_CB<4>
  VSS24  = GND
  CB5_A  = M_H_CPU1_SA_CB<5>
  VSS25  = GND
  ALERT_N  = M_H_CPU1_ALERT_N
  VSS26  = GND
  CS0_A_N  = M_H_CPU1_SA_CS_N<2>
  VSS27  = GND
  CA0_A  = M_H_CPU1_SA_CA<0>
  VSS28  = GND
  CA2_A  = M_H_CPU1_SA_CA<2>
  VSS29  = GND
  CA4_A  = M_H_CPU1_SA_CA<4>
  VSS30  = GND
  CA6_A  = M_H_CPU1_SA_CA<6>
  VSS31  = GND
  PAR_A  = M_H_CPU1_SA_PAR
  VSS32  = GND
  CA0_B  = M_H_CPU1_SB_CA<0>
  VSS33  = GND
  CA2_B  = M_H_CPU1_SB_CA<2>
  VSS34  = GND
  CA4_B  = M_H_CPU1_SB_CA<4>
  VSS35  = GND
  CA6_B  = M_H_CPU1_SB_CA<6>
  VSS36  = GND
  CS0_B_N  = M_H_CPU1_SB_CS_N<2>
  VSS37  = GND
  \lbd||rsp_a_n\  = M_H_CPU1_SA_RSP<1>
  \lbs||rsp_b_n\  = M_H_CPU1_SB_RSP<1>
  VSS38  = GND
  CB4_B  = M_H_CPU1_SB_CB<4>
  VSS39  = GND
  CB5_B  = M_H_CPU1_SB_CB<5>
  VSS40  = GND
  \dqs9_b_t||tdqs9_b_t||dbi4_b_n\  = M_H_CPU1_SB_DQS_DP<9>
  \dqs9_b_c||tdqs9_b_c\  = M_H_CPU1_SB_DQS_DN<9>
  VSS41  = GND
  CB0_B  = M_H_CPU1_SB_CB<0>
  VSS42  = GND
  CB1_B  = M_H_CPU1_SB_CB<1>
  VSS43  = GND
  DQ0_B  = M_H_CPU1_SB_DQ<0>
  VSS44  = GND
  DQ1_B  = M_H_CPU1_SB_DQ<1>
  VSS45  = GND
  DQS0_B_T  = M_H_CPU1_SB_DQS_DP<0>
  DQS0_B_C  = M_H_CPU1_SB_DQS_DN<0>
  VSS46  = GND
  DQ4_B  = M_H_CPU1_SB_DQ<4>
  VSS47  = GND
  DQ5_B  = M_H_CPU1_SB_DQ<5>
  VSS48  = GND
  DQ8_B  = M_H_CPU1_SB_DQ<8>
  VSS49  = GND
  DQ9_B  = M_H_CPU1_SB_DQ<9>
  VSS50  = GND
  DQS1_B_T  = M_H_CPU1_SB_DQS_DP<1>
  DQS1_B_C  = M_H_CPU1_SB_DQS_DN<1>
  VSS51  = GND
  DQ12_B  = M_H_CPU1_SB_DQ<12>
  VSS52  = GND
  DQ13_B  = M_H_CPU1_SB_DQ<13>
  VSS53  = GND
  DQ16_B  = M_H_CPU1_SB_DQ<16>
  VSS54  = GND
  DQ17_B  = M_H_CPU1_SB_DQ<17>
  VSS55  = GND
  DQS2_B_T  = M_H_CPU1_SB_DQS_DP<2>
  DQS2_B_C  = M_H_CPU1_SB_DQS_DN<2>
  VSS56  = GND
  DQ20_B  = M_H_CPU1_SB_DQ<20>
  VSS57  = GND
  DQ21_B  = M_H_CPU1_SB_DQ<21>
  VSS58  = GND
  DQ24_B  = M_H_CPU1_SB_DQ<24>
  VSS59  = GND
  DQ25_B  = M_H_CPU1_SB_DQ<25>
  VSS60  = GND
  DQS3_B_T  = M_H_CPU1_SB_DQS_DP<3>
  DQS3_B_C  = M_H_CPU1_SB_DQS_DN<3>
  VSS61  = GND
  DQ28_B  = M_H_CPU1_SB_DQ<28>
  VSS62  = GND
  DQ29_B  = M_H_CPU1_SB_DQ<29>
  VSS63  = GND
  RFU1  = TP_CHH_CPU1_DIMM2_FRU_1
  VIN_BULK1  = P12V_S3_AUX_CPU1_NVDIMM
  VIN_BULK2  = P12V_S3_AUX_CPU1_NVDIMM
  \pwr_good||fail_n\  = PWRGD_CHH_CPU1_DIMM2
  HSA  = PD_CHH_CPU1_DIMM2_SAA
  RFU2  = TP_CHH_CPU1_DIMM2_FRU_2
  RFU3  = TP_CHH_CPU1_DIMM2_FRU_3
  VSS64  = GND
  DQ2_A  = M_H_CPU1_SA_DQ<2>
  VSS65  = GND
  DQ3_A  = M_H_CPU1_SA_DQ<3>
  VSS66  = GND
  \dqs5_a_c||tdqs5_a_c||dqs5_a_t||tdqs5_a_t\  = M_H_CPU1_SA_DQS_DN<5>
  \dqs5_a_t||tdqs5_a_t\  = M_H_CPU1_SA_DQS_DP<5>
  VSS67  = GND
  DQ6_A  = M_H_CPU1_SA_DQ<6>
  VSS68  = GND
  DQ7_A  = M_H_CPU1_SA_DQ<7>
  VSS69  = GND
  DQ10_A  = M_H_CPU1_SA_DQ<10>
  VSS70  = GND
  DQ11_A  = M_H_CPU1_SA_DQ<11>
  VSS71  = GND
  \dqs6_a_c||tdqs6_a_c||dqs6_a_t||tdqs6_a_t\  = M_H_CPU1_SA_DQS_DN<6>
  \dqs6_a_t||tdqs6_a_t\  = M_H_CPU1_SA_DQS_DP<6>
  VSS72  = GND
  DQ14_A  = M_H_CPU1_SA_DQ<14>
  VSS73  = GND
  DQ15_A  = M_H_CPU1_SA_DQ<15>
  VSS74  = GND
  DQ18_A  = M_H_CPU1_SA_DQ<18>
  VSS75  = GND
  DQ19_A  = M_H_CPU1_SA_DQ<19>
  VSS76  = GND
  \dqs7_a_c||tdqs7_a_c\  = M_H_CPU1_SA_DQS_DN<7>
  \dqs7_a_t||tdqs7_a_t\  = M_H_CPU1_SA_DQS_DP<7>
  VSS77  = GND
  DQ22_A  = M_H_CPU1_SA_DQ<22>
  VSS78  = GND
  DQ23_A  = M_H_CPU1_SA_DQ<23>
  VSS79  = GND
  DQ26_A  = M_H_CPU1_SA_DQ<26>
  VSS80  = GND
  DQ27_A  = M_H_CPU1_SA_DQ<27>
  VSS81  = GND
  \dqs8_a_c||tdqs8_a_c\  = M_H_CPU1_SA_DQS_DN<8>
  \dqs8_a_t||tdqs8_a_t\  = M_H_CPU1_SA_DQS_DP<8>
  VSS82  = GND
  DQ30_A  = M_H_CPU1_SA_DQ<30>
  VSS83  = GND
  DQ31_A  = M_H_CPU1_SA_DQ<31>
  VSS84  = GND
  CB2_A  = M_H_CPU1_SA_CB<2>
  VSS85  = GND
  CB3_A  = M_H_CPU1_SA_CB<3>
  VSS86  = GND
  \dqs9_a_c||tdqs9_a_c\  = M_H_CPU1_SA_DQS_DN<9>
  \dqs9_a_t||tdqs9_a_t\  = M_H_CPU1_SA_DQS_DP<9>
  VSS87  = GND
  CB6_A  = M_H_CPU1_SA_CB<6>
  VSS88  = GND
  CB7_A  = M_H_CPU1_SA_CB<7>
  VSS89  = GND
  RESET_N  = RST_M_GH_CPU1_FPGA_N
  VSS90  = GND
  CS1_A_N  = M_H_CPU1_SA_CS_N<3>
  VSS91  = GND
  CA1_A  = M_H_CPU1_SA_CA<1>
  VSS92  = GND
  CA3_A  = M_H_CPU1_SA_CA<3>
  VSS93  = GND
  CA5_A  = M_H_CPU1_SA_CA<5>
  VSS94  = GND
  CK_T  = M_H_CPU1_CLK_DP<1>
  CK_C  = M_H_CPU1_CLK_DN<1>
  VSS95  = GND
  RFU4  = TP_CHH_CPU1_DIMM2_FRU_4
  CA1_B  = M_H_CPU1_SB_CA<1>
  VSS96  = GND
  CA3_B  = M_H_CPU1_SB_CA<3>
  VSS97  = GND
  CA5_B  = M_H_CPU1_SB_CA<5>
  VSS98  = GND
  PAR_B  = M_H_CPU1_SB_PAR
  VSS99  = GND
  CS1_B_N  = M_H_CPU1_SB_CS_N<3>
  VSS100  = GND
  RFU5  = TP_CHH_CPU1_DIMM2_FRU_5
  RFU6  = TP_CHH_CPU1_DIMM2_FRU_6
  VSS101  = GND
  CB6_B  = M_H_CPU1_SB_CB<6>
  VSS102  = GND
  CB7_B  = M_H_CPU1_SB_CB<7>
  VSS103  = GND
  DQS4_B_C  = M_H_CPU1_SB_DQS_DN<4>
  DQS4_B_T  = M_H_CPU1_SB_DQS_DP<4>
  VSS104  = GND
  CB2_B  = M_H_CPU1_SB_CB<2>
  VSS105  = GND
  CB3_B  = M_H_CPU1_SB_CB<3>
  VSS106  = GND
  DQ2_B  = M_H_CPU1_SB_DQ<2>
  VSS107  = GND
  DQ3_B  = M_H_CPU1_SB_DQ<3>
  VSS108  = GND
  \dqs5_b_c||tdqs5_b_c\  = M_H_CPU1_SB_DQS_DN<5>
  \dqs5_b_t||tdqs5_b_t\  = M_H_CPU1_SB_DQS_DP<5>
  VSS109  = GND
  DQ6_B  = M_H_CPU1_SB_DQ<6>
  VSS110  = GND
  DQ7_B  = M_H_CPU1_SB_DQ<7>
  VSS111  = GND
  DQ10_B  = M_H_CPU1_SB_DQ<10>
  VSS112  = GND
  DQ11_B  = M_H_CPU1_SB_DQ<11>
  VSS113  = GND
  \dqs6_b_c||tdqs6_b_c\  = M_H_CPU1_SB_DQS_DN<6>
  \dqs6_b_t||tdqs6_b_t\  = M_H_CPU1_SB_DQS_DP<6>
  VSS114  = GND
  DQ14_B  = M_H_CPU1_SB_DQ<14>
  VSS115  = GND
  DQ15_B  = M_H_CPU1_SB_DQ<15>
  VSS116  = GND
  DQ18_B  = M_H_CPU1_SB_DQ<18>
  VSS117  = GND
  DQ19_B  = M_H_CPU1_SB_DQ<19>
  VSS118  = GND
  \dqs7_b_c||tdqs7_b_c\  = M_H_CPU1_SB_DQS_DN<7>
  \dqs7_b_t||tdqs7_b_t\  = M_H_CPU1_SB_DQS_DP<7>
  VSS119  = GND
  DQ22_B  = M_H_CPU1_SB_DQ<22>
  VSS120  = GND
  DQ23_B  = M_H_CPU1_SB_DQ<23>
  VSS121  = GND
  DQ26_B  = M_H_CPU1_SB_DQ<26>
  VSS122  = GND
  DQ27_B  = M_H_CPU1_SB_DQ<27>
  VSS123  = GND
  \dqs8_b_c||tdqs8_b_c\  = M_H_CPU1_SB_DQS_DN<8>
  \dqs8_b_t||tdqs8_b_t\  = M_H_CPU1_SB_DQS_DP<8>
  VSS124  = GND
  DQ30_B  = M_H_CPU1_SB_DQ<30>
  VSS125  = GND
  DQ31_B  = M_H_CPU1_SB_DQ<31>
  VSS126  = GND
  G1  = GND
  G2  = GND
  G3  = GND

(kicad_pcb
	(version 20260206)
	(generator "pcbnew")
	(generator_version "10.0")
	(general
		(thickness 1.6)
		(legacy_teardrops no)
	)
	(paper "A4")
	(title_block
		(title "03242023_DA0F0TMBIJ0_F0T_Motherboard_J_brd_V01_OCP.brd")
		(comment 1 "Grand Teton / footprint 3133 of 6105 (J32), pads 46-91 of 291")
	)
	(layers
		(0 "F.Cu" signal "TOP")
		(4 "In1.Cu" signal "GND")
		(6 "In2.Cu" signal "IN1")
		(8 "In3.Cu" signal "GND1")
		(10 "In4.Cu" signal "IN2")
		(12 "In5.Cu" signal "GND2")
		(14 "In6.Cu" signal "IN3")
		(16 "In7.Cu" signal "GND3")
		(18 "In8.Cu" signal "VCC")
		(20 "In9.Cu" signal "VCC1")
		(22 "In10.Cu" signal "GND4")
		(24 "In11.Cu" signal "IN4")
		(26 "In12.Cu" signal "GND5")
		(28 "In13.Cu" signal "IN5")
		(30 "In14.Cu" signal "GND6")
		(32 "In15.Cu" signal "IN6")
		(34 "In16.Cu" signal "GND7")
		(2 "B.Cu" signal "BOTTOM")
		(9 "F.Adhes" user "F.Adhesive")
		(11 "B.Adhes" user "B.Adhesive")
		(13 "F.Paste" user "Package Geometry/Pastemask Top")
		(15 "B.Paste" user "Package Geometry/Pastemask Bottom")
		(5 "F.SilkS" user "Ref Des/Silkscreen Top")
		(7 "B.SilkS" user "Ref Des/Silkscreen Bottom")
		(1 "F.Mask" user "Board Geometry/Soldermask Top")
		(3 "B.Mask" user "Board Geometry/Soldermask Bottom")
		(17 "Dwgs.User" user "User.Drawings")
		(19 "Cmts.User" user "User.Comments")
		(21 "Eco1.User" user "User.Eco1")
		(23 "Eco2.User" user "User.Eco2")
		(25 "Edge.Cuts" user "Board Geometry/Outline")
		(27 "Margin" user)
		(31 "F.CrtYd" user "Package Geometry/Place Bound Top")
		(29 "B.CrtYd" user "Package Geometry/Place Bound Bottom")
		(35 "F.Fab" user "Ref Des/Assembly Top")
		(33 "B.Fab" user "Ref Des/Assembly Bottom")
	)
	(footprint ""
		(layer "F.Cu")
		(at 206.12608 -258.091686)
		(property "Reference" "J32"
			(at 0.68834 -81.826608 0)
			(unlocked yes)
			(layer "F.SilkS")
			(effects
				(font
					(size 0.7874 0.5842)
					(thickness 0.1524)
				)
				(justify left)
			)
		)
		(property "Value" ""
			(at 0 0 0)
			(layer "F.Fab")
			(effects
				(font
					(size 1.27 1.27)
				)
			)
		)
		(duplicate_pad_numbers_are_jumpers no)
		(pad "46" smd rect
			(at -2.050034 -25.07488 270)
			(size 0.519938 1.4986)
			(layers "F.Cu" "F.Mask" "F.Paste")
			(net "GND")
		)
		(pad "47" smd rect
			(at -2.050034 -24.224996 270)
			(size 0.519938 1.4986)
			(layers "F.Cu" "F.Mask" "F.Paste")
			(net "M_H_CPU1_SA_DQ<28>")
		)
		(pad "48" smd rect
			(at -2.050034 -23.375112 270)
			(size 0.519938 1.4986)
			(layers "F.Cu" "F.Mask" "F.Paste")
			(net "GND")
		)
		(pad "49" smd rect
			(at -2.050034 -22.524974 270)
			(size 0.519938 1.4986)
			(layers "F.Cu" "F.Mask" "F.Paste")
			(net "M_H_CPU1_SA_DQ<29>")
		)
		(pad "50" smd rect
			(at -2.050034 -21.67509 270)
			(size 0.519938 1.4986)
			(layers "F.Cu" "F.Mask" "F.Paste")
			(net "GND")
		)
		(pad "51" smd rect
			(at -2.050034 -20.824952 270)
			(size 0.519938 1.4986)
			(layers "F.Cu" "F.Mask" "F.Paste")
			(net "M_H_CPU1_SA_CB<0>")
		)
		(pad "52" smd rect
			(at -2.050034 -19.975068 270)
			(size 0.519938 1.4986)
			(layers "F.Cu" "F.Mask" "F.Paste")
			(net "GND")
		)
		(pad "53" smd rect
			(at -2.050034 -19.12493 270)
			(size 0.519938 1.4986)
			(layers "F.Cu" "F.Mask" "F.Paste")
			(net "M_H_CPU1_SA_CB<1>")
		)
		(pad "54" smd rect
			(at -2.050034 -18.275046 270)
			(size 0.519938 1.4986)
			(layers "F.Cu" "F.Mask" "F.Paste")
			(net "GND")
		)
		(pad "55" smd rect
			(at -2.050034 -17.424908 270)
			(size 0.519938 1.4986)
			(layers "F.Cu" "F.Mask" "F.Paste")
			(net "M_H_CPU1_SA_DQS_DP<4>")
		)
		(pad "56" smd rect
			(at -2.050034 -16.575024 270)
			(size 0.519938 1.4986)
			(layers "F.Cu" "F.Mask" "F.Paste")
			(net "M_H_CPU1_SA_DQS_DN<4>")
		)
		(pad "57" smd rect
			(at -2.050034 -15.724886 270)
			(size 0.519938 1.4986)
			(layers "F.Cu" "F.Mask" "F.Paste")
			(net "GND")
		)
		(pad "58" smd rect
			(at -2.050034 -14.875002 270)
			(size 0.519938 1.4986)
			(layers "F.Cu" "F.Mask" "F.Paste")
			(net "M_H_CPU1_SA_CB<4>")
		)
		(pad "59" smd rect
			(at -2.050034 -14.025118 270)
			(size 0.519938 1.4986)
			(layers "F.Cu" "F.Mask" "F.Paste")
			(net "GND")
		)
		(pad "60" smd rect
			(at -2.050034 -13.17498 270)
			(size 0.519938 1.4986)
			(layers "F.Cu" "F.Mask" "F.Paste")
			(net "M_H_CPU1_SA_CB<5>")
		)
		(pad "61" smd rect
			(at -2.050034 -12.325096 270)
			(size 0.519938 1.4986)
			(layers "F.Cu" "F.Mask" "F.Paste")
			(net "GND")
		)
		(pad "62" smd rect
			(at -2.050034 -11.474958 270)
			(size 0.519938 1.4986)
			(layers "F.Cu" "F.Mask" "F.Paste")
			(net "M_H_CPU1_ALERT_N")
		)
		(pad "63" smd rect
			(at -2.050034 -10.625074 270)
			(size 0.519938 1.4986)
			(layers "F.Cu" "F.Mask" "F.Paste")
			(net "GND")
		)
		(pad "64" smd rect
			(at -2.050034 -9.774936 270)
			(size 0.519938 1.4986)
			(layers "F.Cu" "F.Mask" "F.Paste")
			(net "M_H_CPU1_SA_CS_N<2>")
		)
		(pad "65" smd rect
			(at -2.050034 -8.925052 270)
			(size 0.519938 1.4986)
			(layers "F.Cu" "F.Mask" "F.Paste")
			(net "GND")
		)
		(pad "66" smd rect
			(at -2.050034 -8.074914 270)
			(size 0.519938 1.4986)
			(layers "F.Cu" "F.Mask" "F.Paste")
			(net "M_H_CPU1_SA_CA<0>")
		)
		(pad "67" smd rect
			(at -2.050034 -7.22503 270)
			(size 0.519938 1.4986)
			(layers "F.Cu" "F.Mask" "F.Paste")
			(net "GND")
		)
		(pad "68" smd rect
			(at -2.050034 -6.374892 270)
			(size 0.519938 1.4986)
			(layers "F.Cu" "F.Mask" "F.Paste")
			(net "M_H_CPU1_SA_CA<2>")
		)
		(pad "69" smd rect
			(at -2.050034 -5.525008 270)
			(size 0.519938 1.4986)
			(layers "F.Cu" "F.Mask" "F.Paste")
			(net "GND")
		)
		(pad "70" smd rect
			(at -2.050034 -4.675124 270)
			(size 0.519938 1.4986)
			(layers "F.Cu" "F.Mask" "F.Paste")
			(net "M_H_CPU1_SA_CA<4>")
		)
		(pad "71" smd rect
			(at -2.050034 -3.824986 270)
			(size 0.519938 1.4986)
			(layers "F.Cu" "F.Mask" "F.Paste")
			(net "GND")
		)
		(pad "72" smd rect
			(at -2.050034 -2.975102 270)
			(size 0.519938 1.4986)
			(layers "F.Cu" "F.Mask" "F.Paste")
			(net "M_H_CPU1_SA_CA<6>")
		)
		(pad "73" smd rect
			(at -2.050034 -2.124964 270)
			(size 0.519938 1.4986)
			(layers "F.Cu" "F.Mask" "F.Paste")
			(net "GND")
		)
		(pad "74" smd rect
			(at -2.050034 -1.27508 270)
			(size 0.519938 1.4986)
			(layers "F.Cu" "F.Mask" "F.Paste")
			(net "M_H_CPU1_SA_PAR")
		)
		(pad "75" smd rect
			(at -2.050034 -0.424942 270)
			(size 0.519938 1.4986)
			(layers "F.Cu" "F.Mask" "F.Paste")
			(net "GND")
		)
		(pad "76" smd rect
			(at -2.050034 5.525008 270)
			(size 0.519938 1.4986)
			(layers "F.Cu" "F.Mask" "F.Paste")
			(net "M_H_CPU1_SB_CA<0>")
		)
		(pad "77" smd rect
			(at -2.050034 6.374892 270)
			(size 0.519938 1.4986)
			(layers "F.Cu" "F.Mask" "F.Paste")
			(net "GND")
		)
		(pad "78" smd rect
			(at -2.050034 7.22503 270)
			(size 0.519938 1.4986)
			(layers "F.Cu" "F.Mask" "F.Paste")
			(net "M_H_CPU1_SB_CA<2>")
		)
		(pad "79" smd rect
			(at -2.050034 8.074914 270)
			(size 0.519938 1.4986)
			(layers "F.Cu" "F.Mask" "F.Paste")
			(net "GND")
		)
		(pad "80" smd rect
			(at -2.050034 8.925052 270)
			(size 0.519938 1.4986)
			(layers "F.Cu" "F.Mask" "F.Paste")
			(net "M_H_CPU1_SB_CA<4>")
		)
		(pad "81" smd rect
			(at -2.050034 9.774936 270)
			(size 0.519938 1.4986)
			(layers "F.Cu" "F.Mask" "F.Paste")
			(net "GND")
		)
		(pad "82" smd rect
			(at -2.050034 10.625074 270)
			(size 0.519938 1.4986)
			(layers "F.Cu" "F.Mask" "F.Paste")
			(net "M_H_CPU1_SB_CA<6>")
		)
		(pad "83" smd rect
			(at -2.050034 11.474958 270)
			(size 0.519938 1.4986)
			(layers "F.Cu" "F.Mask" "F.Paste")
			(net "GND")
		)
		(pad "84" smd rect
			(at -2.050034 12.325096 270)
			(size 0.519938 1.4986)
			(layers "F.Cu" "F.Mask" "F.Paste")
			(net "M_H_CPU1_SB_CS_N<2>")
		)
		(pad "85" smd rect
			(at -2.050034 13.17498 270)
			(size 0.519938 1.4986)
			(layers "F.Cu" "F.Mask" "F.Paste")
			(net "GND")
		)
		(pad "86" smd rect
			(at -2.050034 14.025118 270)
			(size 0.519938 1.4986)
			(layers "F.Cu" "F.Mask" "F.Paste")
			(net "M_H_CPU1_SA_RSP<1>")
		)
		(pad "87" smd rect
			(at -2.050034 14.875002 270)
			(size 0.519938 1.4986)
			(layers "F.Cu" "F.Mask" "F.Paste")
			(net "M_H_CPU1_SB_RSP<1>")
		)
		(pad "88" smd rect
			(at -2.050034 15.724886 270)
			(size 0.519938 1.4986)
			(layers "F.Cu" "F.Mask" "F.Paste")
			(net "GND")
		)
		(pad "89" smd rect
			(at -2.050034 16.575024 270)
			(size 0.519938 1.4986)
			(layers "F.Cu" "F.Mask" "F.Paste")
			(net "M_H_CPU1_SB_CB<4>")
		)
		(pad "90" smd rect
			(at -2.050034 17.424908 270)
			(size 0.519938 1.4986)
			(layers "F.Cu" "F.Mask" "F.Paste")
			(net "GND")
		)
		(pad "91" smd rect
			(at -2.050034 18.275046 270)
			(size 0.519938 1.4986)
			(layers "F.Cu" "F.Mask" "F.Paste")
			(net "M_H_CPU1_SB_CB<5>")
		)
	)
)
